# S9S_MB_2U (Grand Teton) — schematic netlist excerpt (pin names and nets, part order shuffled) for the footprints in the layout excerpt that follows; sources: Cadence DE-HDL packaged netlist, KiCad conversion of 03242023_DA0F0TMBIJ0_F0T_Motherboard_J_brd_V01_OCP.brd

C497  Q_CAP  47UF 4V 20% X6S  pkg C0805  page 75 : A = PVCCFA_EHV_FIVRA_CPU0 ; B = GND
R2556  Q_RES  1K 1% CHIP  pkg 0402LF  page 292 : A = P3V3_AUX ; B = PWRGD_PVCCINFAON_CPU1_R
C1898  Q_CAP  0.01UF 50V 10% X7R  pkg C0402  page 217 : A = P3V3_AUX_FPGA_VCCIO5 ; B = GND

(kicad_pcb
	(version 20260206)
	(generator "pcbnew")
	(generator_version "10.0")
	(general
		(thickness 1.6)
		(legacy_teardrops no)
	)
	(paper "A4")
	(title_block
		(title "03242023_DA0F0TMBIJ0_F0T_Motherboard_J_brd_V01_OCP.brd")
		(comment 1 "Grand Teton / footprints 5875-5877 of 6105")
	)
	(layers
		(0 "F.Cu" signal "TOP")
		(4 "In1.Cu" signal "GND")
		(6 "In2.Cu" signal "IN1")
		(8 "In3.Cu" signal "GND1")
		(10 "In4.Cu" signal "IN2")
		(12 "In5.Cu" signal "GND2")
		(14 "In6.Cu" signal "IN3")
		(16 "In7.Cu" signal "GND3")
		(18 "In8.Cu" signal "VCC")
		(20 "In9.Cu" signal "VCC1")
		(22 "In10.Cu" signal "GND4")
		(24 "In11.Cu" signal "IN4")
		(26 "In12.Cu" signal "GND5")
		(28 "In13.Cu" signal "IN5")
		(30 "In14.Cu" signal "GND6")
		(32 "In15.Cu" signal "IN6")
		(34 "In16.Cu" signal "GND7")
		(2 "B.Cu" signal "BOTTOM")
		(9 "F.Adhes" user "F.Adhesive")
		(11 "B.Adhes" user "B.Adhesive")
		(13 "F.Paste" user "Package Geometry/Pastemask Top")
		(15 "B.Paste" user "Package Geometry/Pastemask Bottom")
		(5 "F.SilkS" user "Ref Des/Silkscreen Top")
		(7 "B.SilkS" user "Ref Des/Silkscreen Bottom")
		(1 "F.Mask" user "Board Geometry/Soldermask Top")
		(3 "B.Mask" user "Board Geometry/Soldermask Bottom")
		(17 "Dwgs.User" user "User.Drawings")
		(19 "Cmts.User" user "User.Comments")
		(21 "Eco1.User" user "User.Eco1")
		(23 "Eco2.User" user "User.Eco2")
		(25 "Edge.Cuts" user "Board Geometry/Outline")
		(27 "Margin" user)
		(31 "F.CrtYd" user "Package Geometry/Place Bound Top")
		(29 "B.CrtYd" user "Package Geometry/Place Bound Bottom")
		(35 "F.Fab" user "Ref Des/Assembly Top")
		(33 "B.Fab" user "Ref Des/Assembly Bottom")
	)
	(footprint ""
		(layer "B.Cu")
		(at 36.968938 -125.38456)
		(property "Reference" "R2556"
			(at 0 0 0)
			(layer "B.SilkS")
			(hide yes)
			(effects
				(font
					(size 1.27 1.27)
				)
				(justify mirror)
			)
		)
		(property "Value" ""
			(at 0 0 0)
			(layer "B.Fab")
			(effects
				(font
					(size 1.27 1.27)
				)
				(justify mirror)
			)
		)
		(duplicate_pad_numbers_are_jumpers no)
		(fp_line
			(start -0.7874 -0.4064)
			(end -0.7874 0.4064)
			(stroke
				(width 0.1524)
				(type default)
			)
			(layer "B.SilkS")
		)
		(fp_line
			(start -0.7874 0.4064)
			(end 0.7874 0.4064)
			(stroke
				(width 0.1524)
				(type default)
			)
			(layer "B.SilkS")
		)
		(fp_line
			(start 0.7874 -0.4064)
			(end -0.7874 -0.4064)
			(stroke
				(width 0.1524)
				(type default)
			)
			(layer "B.SilkS")
		)
		(fp_line
			(start 0.7874 0.4064)
			(end 0.7874 -0.4064)
			(stroke
				(width 0.1524)
				(type default)
			)
			(layer "B.SilkS")
		)
		(fp_line
			(start -0.67945 -0.3048)
			(end -0.67945 0.3048)
			(stroke
				(width 0.1)
				(type default)
			)
			(layer "B.Fab")
		)
		(fp_line
			(start -0.67945 0.3048)
			(end -0.120396 0.3048)
			(stroke
				(width 0.1)
				(type default)
			)
			(layer "B.Fab")
		)
		(fp_line
			(start -0.12065 -0.3048)
			(end -0.67945 -0.3048)
			(stroke
				(width 0.1)
				(type default)
			)
			(layer "B.Fab")
		)
		(fp_line
			(start -0.12065 -0.2794)
			(end -0.12065 -0.3048)
			(stroke
				(width 0.1)
				(type default)
			)
			(layer "B.Fab")
		)
		(fp_line
			(start -0.120396 0.2794)
			(end 0.12065 0.2794)
			(stroke
				(width 0.1)
				(type default)
			)
			(layer "B.Fab")
		)
		(fp_line
			(start -0.120396 0.3048)
			(end -0.120396 0.2794)
			(stroke
				(width 0.1)
				(type default)
			)
			(layer "B.Fab")
		)
		(fp_line
			(start 0.12065 -0.305054)
			(end 0.12065 -0.2794)
			(stroke
				(width 0.1)
				(type default)
			)
			(layer "B.Fab")
		)
		(fp_line
			(start 0.12065 -0.2794)
			(end -0.12065 -0.2794)
			(stroke
				(width 0.1)
				(type default)
			)
			(layer "B.Fab")
		)
		(fp_line
			(start 0.12065 0.2794)
			(end 0.12065 0.3048)
			(stroke
				(width 0.1)
				(type default)
			)
			(layer "B.Fab")
		)
		(fp_line
			(start 0.12065 0.3048)
			(end 0.67945 0.3048)
			(stroke
				(width 0.1)
				(type default)
			)
			(layer "B.Fab")
		)
		(fp_line
			(start 0.67945 -0.305054)
			(end 0.12065 -0.305054)
			(stroke
				(width 0.1)
				(type default)
			)
			(layer "B.Fab")
		)
		(fp_line
			(start 0.67945 0.3048)
			(end 0.67945 -0.305054)
			(stroke
				(width 0.1)
				(type default)
			)
			(layer "B.Fab")
		)
		(pad "1" smd circle
			(at 0.40005 0 180)
			(size 0 0)
			(layers "B.Cu" "B.Mask" "B.Paste")
			(net "P3V3_AUX")
		)
		(pad "2" smd circle
			(at -0.40005 0 180)
			(size 0 0)
			(layers "B.Cu" "B.Mask" "B.Paste")
			(net "PWRGD_PVCCINFAON_CPU1_R")
		)
	)
	(footprint ""
		(layer "B.Cu")
		(at 176.555654 -110.975394 -90)
		(property "Reference" "C1898"
			(at 0 0 90)
			(layer "B.SilkS")
			(hide yes)
			(effects
				(font
					(size 1.27 1.27)
				)
				(justify mirror)
			)
		)
		(property "Value" ""
			(at 0 0 90)
			(layer "B.Fab")
			(effects
				(font
					(size 1.27 1.27)
				)
				(justify mirror)
			)
		)
		(duplicate_pad_numbers_are_jumpers no)
		(fp_line
			(start -0.69215 0.2921)
			(end 0.69215 0.2921)
			(stroke
				(width 0.1524)
				(type default)
			)
			(layer "B.SilkS")
		)
		(fp_line
			(start 0.69215 0.2921)
			(end 0.69215 -0.2921)
			(stroke
				(width 0.1524)
				(type default)
			)
			(layer "B.SilkS")
		)
		(fp_line
			(start -0.69215 -0.2921)
			(end -0.69215 0.2921)
			(stroke
				(width 0.1524)
				(type default)
			)
			(layer "B.SilkS")
		)
		(fp_line
			(start 0.69215 -0.2921)
			(end -0.69215 -0.2921)
			(stroke
				(width 0.1524)
				(type default)
			)
			(layer "B.SilkS")
		)
		(fp_line
			(start -0.51435 0.2794)
			(end 0.51435 0.2794)
			(stroke
				(width 0.1)
				(type default)
			)
			(layer "B.Fab")
		)
		(fp_line
			(start 0.51435 0.2794)
			(end 0.51435 -0.2794)
			(stroke
				(width 0.1)
				(type default)
			)
			(layer "B.Fab")
		)
		(fp_line
			(start -0.51435 -0.2794)
			(end -0.51435 0.2794)
			(stroke
				(width 0.1)
				(type default)
			)
			(layer "B.Fab")
		)
		(fp_line
			(start 0.51435 -0.2794)
			(end -0.51435 -0.2794)
			(stroke
				(width 0.1)
				(type default)
			)
			(layer "B.Fab")
		)
		(pad "1" smd circle
			(at 0.40005 0 90)
			(size 0 0)
			(layers "B.Cu" "B.Mask" "B.Paste")
			(net "P3V3_AUX_FPGA_VCCIO5")
		)
		(pad "2" smd circle
			(at -0.40005 0 90)
			(size 0 0)
			(layers "B.Cu" "B.Mask" "B.Paste")
			(net "GND")
		)
		(zone
			(layer "B.Cu")
			(hatch none 0.5)
			(connect_pads
				(clearance 0)
			)
			(min_thickness 0.25)
			(keepout
				(tracks not_allowed)
				(vias allowed)
				(pads allowed)
				(copperpour not_allowed)
				(footprints allowed)
			)
			(placement
				(enabled no)
				(sheetname "")
			)
			(fill
				(thermal_gap 0.5)
				(thermal_bridge_width 0.5)
				(island_removal_mode 0)
			)
			(polygon
				(pts
					(xy 176.468024 -110.784894) (xy 176.409858 -110.876334) (xy 176.409858 -111.075724) (xy 176.468024 -111.165894)
					(xy 176.643284 -111.165894) (xy 176.701704 -111.075724) (xy 176.701704 -110.876334) (xy 176.643538 -110.784894)
				)
			)
		)
	)
	(footprint ""
		(layer "B.Cu")
		(at 364.342934 -259.531866 90)
		(property "Reference" "C497"
			(at 0 0 90)
			(layer "B.SilkS")
			(hide yes)
			(effects
				(font
					(size 1.27 1.27)
				)
				(justify mirror)
			)
		)
		(property "Value" ""
			(at 0 0 90)
			(layer "B.Fab")
			(effects
				(font
					(size 1.27 1.27)
				)
				(justify mirror)
			)
		)
		(duplicate_pad_numbers_are_jumpers no)
		(fp_line
			(start 1.524 -0.762)
			(end -1.524 -0.762)
			(stroke
				(width 0.1524)
				(type default)
			)
			(layer "B.SilkS")
		)
		(fp_line
			(start -1.524 -0.762)
			(end -1.524 0.762)
			(stroke
				(width 0.1524)
				(type default)
			)
			(layer "B.SilkS")
		)
		(fp_line
			(start 1.524 0.762)
			(end 1.524 -0.762)
			(stroke
				(width 0.1524)
				(type default)
			)
			(layer "B.SilkS")
		)
		(fp_line
			(start -1.524 0.762)
			(end 1.524 0.762)
			(stroke
				(width 0.1524)
				(type default)
			)
			(layer "B.SilkS")
		)
		(fp_line
			(start 1.1049 -0.724916)
			(end 1.1049 0.724916)
			(stroke
				(width 0.1)
				(type default)
			)
			(layer "B.Fab")
		)
		(fp_line
			(start -1.1049 -0.724916)
			(end 1.1049 -0.724916)
			(stroke
				(width 0.1)
				(type default)
			)
			(layer "B.Fab")
		)
		(fp_line
			(start 1.1049 0.724916)
			(end -1.1049 0.724916)
			(stroke
				(width 0.1)
				(type default)
			)
			(layer "B.Fab")
		)
		(fp_line
			(start -1.1049 0.724916)
			(end -1.1049 -0.724916)
			(stroke
				(width 0.1)
				(type default)
			)
			(layer "B.Fab")
		)
		(pad "1" smd rect
			(at 0.889 0 90)
			(size 1.016 1.27)
			(layers "B.Cu" "B.Mask" "B.Paste")
			(net "PVCCFA_EHV_FIVRA_CPU0")
		)
		(pad "2" smd rect
			(at -0.889 0 90)
			(size 1.016 1.27)
			(layers "B.Cu" "B.Mask" "B.Paste")
			(net "GND")
		)
	)
)
